(kicad_pcb
	(version 20260206)
	(generator "pcbnew")
	(generator_version "10.0")
	(general
		(thickness 1.6)
		(legacy_teardrops no)
	)
	(paper "A4")
	(title_block
		(title "12092022_DA0F0TMDCD0_F0T_Management_Board_D_brd_V3_OCP.brd")
		(comment 1 "Grand Teton / footprints 383-388 of 1440")
	)
	(layers
		(0 "F.Cu" signal "TOP")
		(4 "In1.Cu" signal "GND")
		(6 "In2.Cu" signal "IN1")
		(8 "In3.Cu" signal "GND1")
		(10 "In4.Cu" signal "IN2")
		(12 "In5.Cu" signal "VCC")
		(14 "In6.Cu" signal "VCC1")
		(16 "In7.Cu" signal "IN3")
		(18 "In8.Cu" signal "GND2")
		(20 "In9.Cu" signal "IN4")
		(22 "In10.Cu" signal "GND3")
		(2 "B.Cu" signal "BOTTOM")
		(9 "F.Adhes" user "F.Adhesive")
		(11 "B.Adhes" user "B.Adhesive")
		(13 "F.Paste" user "Package Geometry/Pastemask Top")
		(15 "B.Paste" user "Package Geometry/Pastemask Bottom")
		(5 "F.SilkS" user "Ref Des/Silkscreen Top")
		(7 "B.SilkS" user "Ref Des/Silkscreen Bottom")
		(1 "F.Mask" user "Board Geometry/Soldermask Top")
		(3 "B.Mask" user "Board Geometry/Soldermask Bottom")
		(17 "Dwgs.User" user "User.Drawings")
		(19 "Cmts.User" user "User.Comments")
		(21 "Eco1.User" user "User.Eco1")
		(23 "Eco2.User" user "User.Eco2")
		(25 "Edge.Cuts" user "Board Geometry/Outline")
		(27 "Margin" user)
		(31 "F.CrtYd" user "Package Geometry/Place Bound Top")
		(29 "B.CrtYd" user "Package Geometry/Place Bound Bottom")
		(35 "F.Fab" user "Ref Des/Assembly Top")
		(33 "B.Fab" user "Ref Des/Assembly Bottom")
	)
	(footprint ""
		(layer "F.Cu")
		(at 54.7878 -109.3978 -90)
		(property "Reference" "R860"
			(at 0 0 270)
			(layer "F.SilkS")
			(hide yes)
			(effects
				(font
					(size 1.27 1.27)
				)
			)
		)
		(property "Value" ""
			(at 0 0 270)
			(layer "F.Fab")
			(effects
				(font
					(size 1.27 1.27)
				)
			)
		)
		(duplicate_pad_numbers_are_jumpers no)
		(fp_line
			(start -0.7874 0.4064)
			(end -0.7874 -0.4064)
			(stroke
				(width 0.1524)
				(type default)
			)
			(layer "F.SilkS")
		)
		(fp_line
			(start 0.7874 0.4064)
			(end -0.7874 0.4064)
			(stroke
				(width 0.1524)
				(type default)
			)
			(layer "F.SilkS")
		)
		(fp_line
			(start -0.7874 -0.4064)
			(end 0.7874 -0.4064)
			(stroke
				(width 0.1524)
				(type default)
			)
			(layer "F.SilkS")
		)
		(fp_line
			(start 0.7874 -0.4064)
			(end 0.7874 0.4064)
			(stroke
				(width 0.1524)
				(type default)
			)
			(layer "F.SilkS")
		)
		(fp_line
			(start -0.67945 0.3048)
			(end -0.67945 -0.305054)
			(stroke
				(width 0.1)
				(type default)
			)
			(layer "F.Fab")
		)
		(fp_line
			(start -0.12065 0.3048)
			(end -0.67945 0.3048)
			(stroke
				(width 0.1)
				(type default)
			)
			(layer "F.Fab")
		)
		(fp_line
			(start 0.120396 0.3048)
			(end 0.120396 0.2794)
			(stroke
				(width 0.1)
				(type default)
			)
			(layer "F.Fab")
		)
		(fp_line
			(start 0.67945 0.3048)
			(end 0.120396 0.3048)
			(stroke
				(width 0.1)
				(type default)
			)
			(layer "F.Fab")
		)
		(fp_line
			(start -0.12065 0.2794)
			(end -0.12065 0.3048)
			(stroke
				(width 0.1)
				(type default)
			)
			(layer "F.Fab")
		)
		(fp_line
			(start 0.120396 0.2794)
			(end -0.12065 0.2794)
			(stroke
				(width 0.1)
				(type default)
			)
			(layer "F.Fab")
		)
		(fp_line
			(start -0.12065 -0.2794)
			(end 0.12065 -0.2794)
			(stroke
				(width 0.1)
				(type default)
			)
			(layer "F.Fab")
		)
		(fp_line
			(start 0.12065 -0.2794)
			(end 0.12065 -0.3048)
			(stroke
				(width 0.1)
				(type default)
			)
			(layer "F.Fab")
		)
		(fp_line
			(start 0.12065 -0.3048)
			(end 0.67945 -0.3048)
			(stroke
				(width 0.1)
				(type default)
			)
			(layer "F.Fab")
		)
		(fp_line
			(start 0.67945 -0.3048)
			(end 0.67945 0.3048)
			(stroke
				(width 0.1)
				(type default)
			)
			(layer "F.Fab")
		)
		(fp_line
			(start -0.67945 -0.305054)
			(end -0.12065 -0.305054)
			(stroke
				(width 0.1)
				(type default)
			)
			(layer "F.Fab")
		)
		(fp_line
			(start -0.12065 -0.305054)
			(end -0.12065 -0.2794)
			(stroke
				(width 0.1)
				(type default)
			)
			(layer "F.Fab")
		)
		(pad "1" smd circle
			(at -0.40005 0 270)
			(size 0 0)
			(layers "F.Cu" "F.Mask" "F.Paste")
			(net "SPI_SYS_R_MOSI")
		)
		(pad "2" smd circle
			(at 0.40005 0 270)
			(size 0 0)
			(layers "F.Cu" "F.Mask" "F.Paste")
			(net "SPI_SYS_MUX_MOSI")
		)
	)
	(footprint ""
		(layer "F.Cu")
		(at -7.62 -10.922)
		(property "Reference" "DB6"
			(at -3.5052 -5.552948 0)
			(unlocked yes)
			(layer "F.SilkS")
			(effects
				(font
					(size 0.7874 0.5842)
					(thickness 0.1524)
				)
				(justify left)
			)
		)
		(property "Value" ""
			(at 0 0 0)
			(layer "F.Fab")
			(effects
				(font
					(size 1.27 1.27)
				)
			)
		)
		(duplicate_pad_numbers_are_jumpers no)
		(fp_line
			(start -3.330702 -4.771136)
			(end 3.330702 -4.771136)
			(stroke
				(width 0.1524)
				(type default)
			)
			(layer "F.SilkS")
		)
		(fp_line
			(start 0 4.011168)
			(end -3.330702 -4.771136)
			(stroke
				(width 0.1524)
				(type default)
			)
			(layer "F.SilkS")
		)
		(fp_line
			(start 3.330702 -4.771136)
			(end 0 4.011168)
			(stroke
				(width 0.1524)
				(type default)
			)
			(layer "F.SilkS")
		)
		(fp_line
			(start -3.330702 -4.771136)
			(end 3.330702 -4.771136)
			(stroke
				(width 0.1)
				(type default)
			)
			(layer "F.Fab")
		)
		(fp_line
			(start 0 4.011168)
			(end -3.330702 -4.771136)
			(stroke
				(width 0.1)
				(type default)
			)
			(layer "F.Fab")
		)
		(fp_line
			(start 3.330702 -4.771136)
			(end 0 4.011168)
			(stroke
				(width 0.1)
				(type default)
			)
			(layer "F.Fab")
		)
		(pad "1" thru_hole circle
			(at 0 0)
			(size 2.159 2.159)
			(drill 1.7018)
			(layers "*.Cu" "*.Mask")
			(remove_unused_layers no)
			(net "T_GND")
			(clearance 0.0254)
			(thermal_gap 0.0254)
		)
		(pad "2" thru_hole circle
			(at -1.27 -3.348736)
			(size 2.159 2.159)
			(drill 1.7018)
			(layers "*.Cu" "*.Mask")
			(remove_unused_layers no)
			(net "TDR_SE_50_OHM_BOT")
			(clearance 0.0254)
			(thermal_gap 0.0254)
		)
		(pad "3" thru_hole circle
			(at 1.27 -3.348736)
			(size 2.159 2.159)
			(drill 1.7018)
			(layers "*.Cu" "*.Mask")
			(remove_unused_layers no)
			(net "TDR_SE_50_OHM_BOT")
			(clearance 0.0254)
			(thermal_gap 0.0254)
		)
	)
	(footprint ""
		(layer "F.Cu")
		(at 28.6512 -62.4332 90)
		(property "Reference" "U47"
			(at -3.65887 -1.7272 0)
			(unlocked yes)
			(layer "F.SilkS")
			(effects
				(font
					(size 0.7874 0.5842)
					(thickness 0.1524)
				)
				(justify left)
			)
		)
		(property "Value" ""
			(at 0 0 90)
			(layer "F.Fab")
			(effects
				(font
					(size 1.27 1.27)
				)
			)
		)
		(duplicate_pad_numbers_are_jumpers no)
		(fp_line
			(start 1.38176 -1.100074)
			(end 0.592074 -1.100074)
			(stroke
				(width 0.1524)
				(type default)
			)
			(layer "F.SilkS")
		)
		(fp_line
			(start 0.592074 -1.100074)
			(end 0 -0.508)
			(stroke
				(width 0.1524)
				(type default)
			)
			(layer "F.SilkS")
		)
		(fp_line
			(start -0.592074 -1.100074)
			(end -1.38176 -1.100074)
			(stroke
				(width 0.1524)
				(type default)
			)
			(layer "F.SilkS")
		)
		(fp_line
			(start -1.38176 -1.100074)
			(end -1.38176 1.100074)
			(stroke
				(width 0.1524)
				(type default)
			)
			(layer "F.SilkS")
		)
		(fp_line
			(start 0 -0.508)
			(end -0.592074 -1.100074)
			(stroke
				(width 0.1524)
				(type default)
			)
			(layer "F.SilkS")
		)
		(fp_line
			(start 1.38176 1.100074)
			(end 1.38176 -1.100074)
			(stroke
				(width 0.1524)
				(type default)
			)
			(layer "F.SilkS")
		)
		(fp_line
			(start -1.38176 1.100074)
			(end 1.38176 1.100074)
			(stroke
				(width 0.1524)
				(type default)
			)
			(layer "F.SilkS")
		)
		(fp_poly
			(pts
				(xy -1.9431 -0.870204) (xy -1.50241 -0.649986) (xy -1.9431 -0.429768)
			)
			(stroke
				(width 0)
				(type default)
			)
			(fill yes)
			(layer "F.SilkS")
		)
		(fp_line
			(start 0.674878 -1.100074)
			(end -0.674878 -1.100074)
			(stroke
				(width 0.1)
				(type default)
			)
			(layer "F.Fab")
		)
		(fp_line
			(start -0.674878 -1.100074)
			(end -0.674878 1.100074)
			(stroke
				(width 0.1)
				(type default)
			)
			(layer "F.Fab")
		)
		(fp_line
			(start 0.674878 1.100074)
			(end 0.674878 -1.100074)
			(stroke
				(width 0.1)
				(type default)
			)
			(layer "F.Fab")
		)
		(fp_line
			(start -0.674878 1.100074)
			(end 0.674878 1.100074)
			(stroke
				(width 0.1)
				(type default)
			)
			(layer "F.Fab")
		)
		(fp_poly
			(pts
				(xy -1.9431 -0.870204) (xy -1.50241 -0.649986) (xy -1.9431 -0.429768)
			)
			(stroke
				(width 0)
				(type default)
			)
			(fill yes)
			(layer "F.Fab")
		)
		(pad "1" smd rect
			(at -0.94996 -0.649986)
			(size 0.4318 0.6096)
			(layers "F.Cu" "F.Mask" "F.Paste")
			(net "UART_BMC_5_TXD_R")
		)
		(pad "2" smd rect
			(at -0.94996 0)
			(size 0.4318 0.6096)
			(layers "F.Cu" "F.Mask" "F.Paste")
			(net "GND")
		)
		(pad "3" smd rect
			(at -0.94996 0.649986)
			(size 0.4318 0.6096)
			(layers "F.Cu" "F.Mask" "F.Paste")
			(net "UART_BMC_5_RXD_BUF1")
		)
		(pad "4" smd rect
			(at 0.94996 0.649986)
			(size 0.4318 0.6096)
			(layers "F.Cu" "F.Mask" "F.Paste")
			(net "UART_BMC_5_RXD_BUF1_R")
		)
		(pad "5" smd rect
			(at 0.94996 0)
			(size 0.4318 0.6096)
			(layers "F.Cu" "F.Mask" "F.Paste")
			(net "P3V3_AUX")
		)
		(pad "6" smd rect
			(at 0.94996 -0.649986)
			(size 0.4318 0.6096)
			(layers "F.Cu" "F.Mask" "F.Paste")
			(net "UART_BMC_5_TXD_BUF1")
		)
	)
	(footprint ""
		(layer "F.Cu")
		(at 70.358 -19.685 90)
		(property "Reference" "R858"
			(at 0 0 90)
			(layer "F.SilkS")
			(hide yes)
			(effects
				(font
					(size 1.27 1.27)
				)
			)
		)
		(property "Value" ""
			(at 0 0 90)
			(layer "F.Fab")
			(effects
				(font
					(size 1.27 1.27)
				)
			)
		)
		(duplicate_pad_numbers_are_jumpers no)
		(fp_line
			(start 0.7874 -0.4064)
			(end 0.7874 0.4064)
			(stroke
				(width 0.1524)
				(type default)
			)
			(layer "F.SilkS")
		)
		(fp_line
			(start -0.7874 -0.4064)
			(end 0.7874 -0.4064)
			(stroke
				(width 0.1524)
				(type default)
			)
			(layer "F.SilkS")
		)
		(fp_line
			(start 0.7874 0.4064)
			(end -0.7874 0.4064)
			(stroke
				(width 0.1524)
				(type default)
			)
			(layer "F.SilkS")
		)
		(fp_line
			(start -0.7874 0.4064)
			(end -0.7874 -0.4064)
			(stroke
				(width 0.1524)
				(type default)
			)
			(layer "F.SilkS")
		)
		(fp_line
			(start -0.12065 -0.305054)
			(end -0.12065 -0.2794)
			(stroke
				(width 0.1)
				(type default)
			)
			(layer "F.Fab")
		)
		(fp_line
			(start -0.67945 -0.305054)
			(end -0.12065 -0.305054)
			(stroke
				(width 0.1)
				(type default)
			)
			(layer "F.Fab")
		)
		(fp_line
			(start 0.67945 -0.3048)
			(end 0.67945 0.3048)
			(stroke
				(width 0.1)
				(type default)
			)
			(layer "F.Fab")
		)
		(fp_line
			(start 0.12065 -0.3048)
			(end 0.67945 -0.3048)
			(stroke
				(width 0.1)
				(type default)
			)
			(layer "F.Fab")
		)
		(fp_line
			(start 0.12065 -0.2794)
			(end 0.12065 -0.3048)
			(stroke
				(width 0.1)
				(type default)
			)
			(layer "F.Fab")
		)
		(fp_line
			(start -0.12065 -0.2794)
			(end 0.12065 -0.2794)
			(stroke
				(width 0.1)
				(type default)
			)
			(layer "F.Fab")
		)
		(fp_line
			(start 0.120396 0.2794)
			(end -0.12065 0.2794)
			(stroke
				(width 0.1)
				(type default)
			)
			(layer "F.Fab")
		)
		(fp_line
			(start -0.12065 0.2794)
			(end -0.12065 0.3048)
			(stroke
				(width 0.1)
				(type default)
			)
			(layer "F.Fab")
		)
		(fp_line
			(start 0.67945 0.3048)
			(end 0.120396 0.3048)
			(stroke
				(width 0.1)
				(type default)
			)
			(layer "F.Fab")
		)
		(fp_line
			(start 0.120396 0.3048)
			(end 0.120396 0.2794)
			(stroke
				(width 0.1)
				(type default)
			)
			(layer "F.Fab")
		)
		(fp_line
			(start -0.12065 0.3048)
			(end -0.67945 0.3048)
			(stroke
				(width 0.1)
				(type default)
			)
			(layer "F.Fab")
		)
		(fp_line
			(start -0.67945 0.3048)
			(end -0.67945 -0.305054)
			(stroke
				(width 0.1)
				(type default)
			)
			(layer "F.Fab")
		)
		(pad "1" smd circle
			(at -0.40005 0 90)
			(size 0 0)
			(layers "F.Cu" "F.Mask" "F.Paste")
			(net "P1V8_AUX")
		)
		(pad "2" smd circle
			(at 0.40005 0 90)
			(size 0 0)
			(layers "F.Cu" "F.Mask" "F.Paste")
			(net "FM_BOARD_BMC_REV_ID0")
		)
	)
	(footprint ""
		(layer "F.Cu")
		(at 54.84368 -24.887936)
		(property "Reference" "R377"
			(at 0 0 0)
			(layer "F.SilkS")
			(hide yes)
			(effects
				(font
					(size 1.27 1.27)
				)
			)
		)
		(property "Value" ""
			(at 0 0 0)
			(layer "F.Fab")
			(effects
				(font
					(size 1.27 1.27)
				)
			)
		)
		(duplicate_pad_numbers_are_jumpers no)
		(fp_line
			(start -0.7874 -0.4064)
			(end 0.7874 -0.4064)
			(stroke
				(width 0.1524)
				(type default)
			)
			(layer "F.SilkS")
		)
		(fp_line
			(start -0.7874 0.4064)
			(end -0.7874 -0.4064)
			(stroke
				(width 0.1524)
				(type default)
			)
			(layer "F.SilkS")
		)
		(fp_line
			(start 0.7874 -0.4064)
			(end 0.7874 0.4064)
			(stroke
				(width 0.1524)
				(type default)
			)
			(layer "F.SilkS")
		)
		(fp_line
			(start 0.7874 0.4064)
			(end -0.7874 0.4064)
			(stroke
				(width 0.1524)
				(type default)
			)
			(layer "F.SilkS")
		)
		(fp_line
			(start -0.67945 -0.305054)
			(end -0.12065 -0.305054)
			(stroke
				(width 0.1)
				(type default)
			)
			(layer "F.Fab")
		)
		(fp_line
			(start -0.67945 0.3048)
			(end -0.67945 -0.305054)
			(stroke
				(width 0.1)
				(type default)
			)
			(layer "F.Fab")
		)
		(fp_line
			(start -0.12065 -0.305054)
			(end -0.12065 -0.2794)
			(stroke
				(width 0.1)
				(type default)
			)
			(layer "F.Fab")
		)
		(fp_line
			(start -0.12065 -0.2794)
			(end 0.12065 -0.2794)
			(stroke
				(width 0.1)
				(type default)
			)
			(layer "F.Fab")
		)
		(fp_line
			(start -0.12065 0.2794)
			(end -0.12065 0.3048)
			(stroke
				(width 0.1)
				(type default)
			)
			(layer "F.Fab")
		)
		(fp_line
			(start -0.12065 0.3048)
			(end -0.67945 0.3048)
			(stroke
				(width 0.1)
				(type default)
			)
			(layer "F.Fab")
		)
		(fp_line
			(start 0.120396 0.2794)
			(end -0.12065 0.2794)
			(stroke
				(width 0.1)
				(type default)
			)
			(layer "F.Fab")
		)
		(fp_line
			(start 0.120396 0.3048)
			(end 0.120396 0.2794)
			(stroke
				(width 0.1)
				(type default)
			)
			(layer "F.Fab")
		)
		(fp_line
			(start 0.12065 -0.3048)
			(end 0.67945 -0.3048)
			(stroke
				(width 0.1)
				(type default)
			)
			(layer "F.Fab")
		)
		(fp_line
			(start 0.12065 -0.2794)
			(end 0.12065 -0.3048)
			(stroke
				(width 0.1)
				(type default)
			)
			(layer "F.Fab")
		)
		(fp_line
			(start 0.67945 -0.3048)
			(end 0.67945 0.3048)
			(stroke
				(width 0.1)
				(type default)
			)
			(layer "F.Fab")
		)
		(fp_line
			(start 0.67945 0.3048)
			(end 0.120396 0.3048)
			(stroke
				(width 0.1)
				(type default)
			)
			(layer "F.Fab")
		)
		(pad "1" smd circle
			(at -0.40005 0)
			(size 0 0)
			(layers "F.Cu" "F.Mask" "F.Paste")
			(net "USB_OC0_EN")
		)
		(pad "2" smd circle
			(at 0.40005 0)
			(size 0 0)
			(layers "F.Cu" "F.Mask" "F.Paste")
			(net "GND")
		)
	)
	(footprint ""
		(layer "F.Cu")
		(at 80.280764 -26.496772 -90)
		(property "Reference" "R603"
			(at 0 0 270)
			(layer "F.SilkS")
			(hide yes)
			(effects
				(font
					(size 1.27 1.27)
				)
			)
		)
		(property "Value" ""
			(at 0 0 270)
			(layer "F.Fab")
			(effects
				(font
					(size 1.27 1.27)
				)
			)
		)
		(duplicate_pad_numbers_are_jumpers no)
		(fp_line
			(start -0.7874 0.4064)
			(end -0.7874 -0.4064)
			(stroke
				(width 0.1524)
				(type default)
			)
			(layer "F.SilkS")
		)
		(fp_line
			(start 0.7874 0.4064)
			(end -0.7874 0.4064)
			(stroke
				(width 0.1524)
				(type default)
			)
			(layer "F.SilkS")
		)
		(fp_line
			(start -0.7874 -0.4064)
			(end 0.7874 -0.4064)
			(stroke
				(width 0.1524)
				(type default)
			)
			(layer "F.SilkS")
		)
		(fp_line
			(start 0.7874 -0.4064)
			(end 0.7874 0.4064)
			(stroke
				(width 0.1524)
				(type default)
			)
			(layer "F.SilkS")
		)
		(fp_line
			(start -0.67945 0.3048)
			(end -0.67945 -0.305054)
			(stroke
				(width 0.1)
				(type default)
			)
			(layer "F.Fab")
		)
		(fp_line
			(start -0.12065 0.3048)
			(end -0.67945 0.3048)
			(stroke
				(width 0.1)
				(type default)
			)
			(layer "F.Fab")
		)
		(fp_line
			(start 0.120396 0.3048)
			(end 0.120396 0.2794)
			(stroke
				(width 0.1)
				(type default)
			)
			(layer "F.Fab")
		)
		(fp_line
			(start 0.67945 0.3048)
			(end 0.120396 0.3048)
			(stroke
				(width 0.1)
				(type default)
			)
			(layer "F.Fab")
		)
		(fp_line
			(start -0.12065 0.2794)
			(end -0.12065 0.3048)
			(stroke
				(width 0.1)
				(type default)
			)
			(layer "F.Fab")
		)
		(fp_line
			(start 0.120396 0.2794)
			(end -0.12065 0.2794)
			(stroke
				(width 0.1)
				(type default)
			)
			(layer "F.Fab")
		)
		(fp_line
			(start -0.12065 -0.2794)
			(end 0.12065 -0.2794)
			(stroke
				(width 0.1)
				(type default)
			)
			(layer "F.Fab")
		)
		(fp_line
			(start 0.12065 -0.2794)
			(end 0.12065 -0.3048)
			(stroke
				(width 0.1)
				(type default)
			)
			(layer "F.Fab")
		)
		(fp_line
			(start 0.12065 -0.3048)
			(end 0.67945 -0.3048)
			(stroke
				(width 0.1)
				(type default)
			)
			(layer "F.Fab")
		)
		(fp_line
			(start 0.67945 -0.3048)
			(end 0.67945 0.3048)
			(stroke
				(width 0.1)
				(type default)
			)
			(layer "F.Fab")
		)
		(fp_line
			(start -0.67945 -0.305054)
			(end -0.12065 -0.305054)
			(stroke
				(width 0.1)
				(type default)
			)
			(layer "F.Fab")
		)
		(fp_line
			(start -0.12065 -0.305054)
			(end -0.12065 -0.2794)
			(stroke
				(width 0.1)
				(type default)
			)
			(layer "F.Fab")
		)
		(pad "1" smd circle
			(at -0.40005 0 270)
			(size 0 0)
			(layers "F.Cu" "F.Mask" "F.Paste")
			(net "LED_POSTCODE_1")
		)
		(pad "2" smd circle
			(at 0.40005 0 270)
			(size 0 0)
			(layers "F.Cu" "F.Mask" "F.Paste")
			(net "LED_POSTCODE_1_R")
		)
	)
)
